(kicad_pcb
	(version 20260206)
	(generator "pcbnew")
	(generator_version "10.0")
	(general
		(thickness 1.6)
		(legacy_teardrops no)
	)
	(paper "A4")
	(title_block
		(title "03242023_DA0F0TMBIJ0_F0T_Motherboard_J_brd_V01_OCP.brd")
		(comment 1 "Grand Teton / footprints 1873-1878 of 6105")
	)
	(layers
		(0 "F.Cu" signal "TOP")
		(4 "In1.Cu" signal "GND")
		(6 "In2.Cu" signal "IN1")
		(8 "In3.Cu" signal "GND1")
		(10 "In4.Cu" signal "IN2")
		(12 "In5.Cu" signal "GND2")
		(14 "In6.Cu" signal "IN3")
		(16 "In7.Cu" signal "GND3")
		(18 "In8.Cu" signal "VCC")
		(20 "In9.Cu" signal "VCC1")
		(22 "In10.Cu" signal "GND4")
		(24 "In11.Cu" signal "IN4")
		(26 "In12.Cu" signal "GND5")
		(28 "In13.Cu" signal "IN5")
		(30 "In14.Cu" signal "GND6")
		(32 "In15.Cu" signal "IN6")
		(34 "In16.Cu" signal "GND7")
		(2 "B.Cu" signal "BOTTOM")
		(9 "F.Adhes" user "F.Adhesive")
		(11 "B.Adhes" user "B.Adhesive")
		(13 "F.Paste" user "Package Geometry/Pastemask Top")
		(15 "B.Paste" user "Package Geometry/Pastemask Bottom")
		(5 "F.SilkS" user "Ref Des/Silkscreen Top")
		(7 "B.SilkS" user "Ref Des/Silkscreen Bottom")
		(1 "F.Mask" user "Board Geometry/Soldermask Top")
		(3 "B.Mask" user "Board Geometry/Soldermask Bottom")
		(17 "Dwgs.User" user "User.Drawings")
		(19 "Cmts.User" user "User.Comments")
		(21 "Eco1.User" user "User.Eco1")
		(23 "Eco2.User" user "User.Eco2")
		(25 "Edge.Cuts" user "Board Geometry/Outline")
		(27 "Margin" user)
		(31 "F.CrtYd" user "Package Geometry/Place Bound Top")
		(29 "B.CrtYd" user "Package Geometry/Place Bound Bottom")
		(35 "F.Fab" user "Ref Des/Assembly Top")
		(33 "B.Fab" user "Ref Des/Assembly Bottom")
	)
	(footprint ""
		(layer "F.Cu")
		(at 424.204892 -389.600948)
		(property "Reference" "R2933"
			(at 0 0 0)
			(layer "F.SilkS")
			(hide yes)
			(effects
				(font
					(size 1.27 1.27)
				)
			)
		)
		(property "Value" ""
			(at 0 0 0)
			(layer "F.Fab")
			(effects
				(font
					(size 1.27 1.27)
				)
			)
		)
		(duplicate_pad_numbers_are_jumpers no)
		(fp_line
			(start -0.7874 -0.4064)
			(end 0.7874 -0.4064)
			(stroke
				(width 0.1524)
				(type default)
			)
			(layer "F.SilkS")
		)
		(fp_line
			(start -0.7874 0.4064)
			(end -0.7874 -0.4064)
			(stroke
				(width 0.1524)
				(type default)
			)
			(layer "F.SilkS")
		)
		(fp_line
			(start 0.7874 -0.4064)
			(end 0.7874 0.4064)
			(stroke
				(width 0.1524)
				(type default)
			)
			(layer "F.SilkS")
		)
		(fp_line
			(start 0.7874 0.4064)
			(end -0.7874 0.4064)
			(stroke
				(width 0.1524)
				(type default)
			)
			(layer "F.SilkS")
		)
		(fp_line
			(start -0.67945 -0.305054)
			(end -0.12065 -0.305054)
			(stroke
				(width 0.1)
				(type default)
			)
			(layer "F.Fab")
		)
		(fp_line
			(start -0.67945 0.3048)
			(end -0.67945 -0.305054)
			(stroke
				(width 0.1)
				(type default)
			)
			(layer "F.Fab")
		)
		(fp_line
			(start -0.12065 -0.305054)
			(end -0.12065 -0.2794)
			(stroke
				(width 0.1)
				(type default)
			)
			(layer "F.Fab")
		)
		(fp_line
			(start -0.12065 -0.2794)
			(end 0.12065 -0.2794)
			(stroke
				(width 0.1)
				(type default)
			)
			(layer "F.Fab")
		)
		(fp_line
			(start -0.12065 0.2794)
			(end -0.12065 0.3048)
			(stroke
				(width 0.1)
				(type default)
			)
			(layer "F.Fab")
		)
		(fp_line
			(start -0.12065 0.3048)
			(end -0.67945 0.3048)
			(stroke
				(width 0.1)
				(type default)
			)
			(layer "F.Fab")
		)
		(fp_line
			(start 0.120396 0.2794)
			(end -0.12065 0.2794)
			(stroke
				(width 0.1)
				(type default)
			)
			(layer "F.Fab")
		)
		(fp_line
			(start 0.120396 0.3048)
			(end 0.120396 0.2794)
			(stroke
				(width 0.1)
				(type default)
			)
			(layer "F.Fab")
		)
		(fp_line
			(start 0.12065 -0.3048)
			(end 0.67945 -0.3048)
			(stroke
				(width 0.1)
				(type default)
			)
			(layer "F.Fab")
		)
		(fp_line
			(start 0.12065 -0.2794)
			(end 0.12065 -0.3048)
			(stroke
				(width 0.1)
				(type default)
			)
			(layer "F.Fab")
		)
		(fp_line
			(start 0.67945 -0.3048)
			(end 0.67945 0.3048)
			(stroke
				(width 0.1)
				(type default)
			)
			(layer "F.Fab")
		)
		(fp_line
			(start 0.67945 0.3048)
			(end 0.120396 0.3048)
			(stroke
				(width 0.1)
				(type default)
			)
			(layer "F.Fab")
		)
		(pad "1" smd circle
			(at -0.40005 0)
			(size 0 0)
			(layers "F.Cu" "F.Mask" "F.Paste")
			(net "P3V3_AUX")
		)
		(pad "2" smd circle
			(at 0.40005 0)
			(size 0 0)
			(layers "F.Cu" "F.Mask" "F.Paste")
			(net "FM_SWB_BIC_READY_ISO_N")
		)
	)
	(footprint ""
		(layer "F.Cu")
		(at 50.785014 -160.800542 90)
		(property "Reference" "PC442_P1_1"
			(at 0 0 90)
			(layer "F.SilkS")
			(hide yes)
			(effects
				(font
					(size 1.27 1.27)
				)
			)
		)
		(property "Value" ""
			(at 0 0 90)
			(layer "F.Fab")
			(effects
				(font
					(size 1.27 1.27)
				)
			)
		)
		(duplicate_pad_numbers_are_jumpers no)
		(fp_line
			(start 0.7874 -0.4064)
			(end 0.7874 0.4064)
			(stroke
				(width 0.1524)
				(type default)
			)
			(layer "F.SilkS")
		)
		(fp_line
			(start -0.7874 -0.4064)
			(end 0.7874 -0.4064)
			(stroke
				(width 0.1524)
				(type default)
			)
			(layer "F.SilkS")
		)
		(fp_line
			(start 0.7874 0.4064)
			(end -0.7874 0.4064)
			(stroke
				(width 0.1524)
				(type default)
			)
			(layer "F.SilkS")
		)
		(fp_line
			(start -0.7874 0.4064)
			(end -0.7874 -0.4064)
			(stroke
				(width 0.1524)
				(type default)
			)
			(layer "F.SilkS")
		)
		(fp_line
			(start -0.12065 -0.305054)
			(end -0.12065 -0.2794)
			(stroke
				(width 0.1)
				(type default)
			)
			(layer "F.Fab")
		)
		(fp_line
			(start -0.67945 -0.305054)
			(end -0.12065 -0.305054)
			(stroke
				(width 0.1)
				(type default)
			)
			(layer "F.Fab")
		)
		(fp_line
			(start 0.67945 -0.3048)
			(end 0.67945 0.3048)
			(stroke
				(width 0.1)
				(type default)
			)
			(layer "F.Fab")
		)
		(fp_line
			(start 0.12065 -0.3048)
			(end 0.67945 -0.3048)
			(stroke
				(width 0.1)
				(type default)
			)
			(layer "F.Fab")
		)
		(fp_line
			(start 0.12065 -0.2794)
			(end 0.12065 -0.3048)
			(stroke
				(width 0.1)
				(type default)
			)
			(layer "F.Fab")
		)
		(fp_line
			(start -0.12065 -0.2794)
			(end 0.12065 -0.2794)
			(stroke
				(width 0.1)
				(type default)
			)
			(layer "F.Fab")
		)
		(fp_line
			(start 0.120396 0.2794)
			(end -0.12065 0.2794)
			(stroke
				(width 0.1)
				(type default)
			)
			(layer "F.Fab")
		)
		(fp_line
			(start -0.12065 0.2794)
			(end -0.12065 0.3048)
			(stroke
				(width 0.1)
				(type default)
			)
			(layer "F.Fab")
		)
		(fp_line
			(start 0.67945 0.3048)
			(end 0.120396 0.3048)
			(stroke
				(width 0.1)
				(type default)
			)
			(layer "F.Fab")
		)
		(fp_line
			(start 0.120396 0.3048)
			(end 0.120396 0.2794)
			(stroke
				(width 0.1)
				(type default)
			)
			(layer "F.Fab")
		)
		(fp_line
			(start -0.12065 0.3048)
			(end -0.67945 0.3048)
			(stroke
				(width 0.1)
				(type default)
			)
			(layer "F.Fab")
		)
		(fp_line
			(start -0.67945 0.3048)
			(end -0.67945 -0.305054)
			(stroke
				(width 0.1)
				(type default)
			)
			(layer "F.Fab")
		)
		(pad "1" smd circle
			(at -0.40005 0 90)
			(size 0 0)
			(layers "F.Cu" "F.Mask" "F.Paste")
			(net "SW_P12V_PVCCINFAON_CPU1_FLT")
		)
		(pad "2" smd circle
			(at 0.40005 0 90)
			(size 0 0)
			(layers "F.Cu" "F.Mask" "F.Paste")
			(net "GND")
		)
	)
	(footprint ""
		(layer "F.Cu")
		(at 131.466844 -131.310126 180)
		(property "Reference" "R651"
			(at 0 0 180)
			(layer "F.SilkS")
			(hide yes)
			(effects
				(font
					(size 1.27 1.27)
				)
			)
		)
		(property "Value" ""
			(at 0 0 180)
			(layer "F.Fab")
			(effects
				(font
					(size 1.27 1.27)
				)
			)
		)
		(duplicate_pad_numbers_are_jumpers no)
		(fp_line
			(start 0.7874 0.4064)
			(end -0.7874 0.4064)
			(stroke
				(width 0.1524)
				(type default)
			)
			(layer "F.SilkS")
		)
		(fp_line
			(start 0.7874 -0.4064)
			(end 0.7874 0.4064)
			(stroke
				(width 0.1524)
				(type default)
			)
			(layer "F.SilkS")
		)
		(fp_line
			(start -0.7874 0.4064)
			(end -0.7874 -0.4064)
			(stroke
				(width 0.1524)
				(type default)
			)
			(layer "F.SilkS")
		)
		(fp_line
			(start -0.7874 -0.4064)
			(end 0.7874 -0.4064)
			(stroke
				(width 0.1524)
				(type default)
			)
			(layer "F.SilkS")
		)
		(fp_line
			(start 0.67945 0.3048)
			(end 0.120396 0.3048)
			(stroke
				(width 0.1)
				(type default)
			)
			(layer "F.Fab")
		)
		(fp_line
			(start 0.67945 -0.3048)
			(end 0.67945 0.3048)
			(stroke
				(width 0.1)
				(type default)
			)
			(layer "F.Fab")
		)
		(fp_line
			(start 0.12065 -0.2794)
			(end 0.12065 -0.3048)
			(stroke
				(width 0.1)
				(type default)
			)
			(layer "F.Fab")
		)
		(fp_line
			(start 0.12065 -0.3048)
			(end 0.67945 -0.3048)
			(stroke
				(width 0.1)
				(type default)
			)
			(layer "F.Fab")
		)
		(fp_line
			(start 0.120396 0.3048)
			(end 0.120396 0.2794)
			(stroke
				(width 0.1)
				(type default)
			)
			(layer "F.Fab")
		)
		(fp_line
			(start 0.120396 0.2794)
			(end -0.12065 0.2794)
			(stroke
				(width 0.1)
				(type default)
			)
			(layer "F.Fab")
		)
		(fp_line
			(start -0.12065 0.3048)
			(end -0.67945 0.3048)
			(stroke
				(width 0.1)
				(type default)
			)
			(layer "F.Fab")
		)
		(fp_line
			(start -0.12065 0.2794)
			(end -0.12065 0.3048)
			(stroke
				(width 0.1)
				(type default)
			)
			(layer "F.Fab")
		)
		(fp_line
			(start -0.12065 -0.2794)
			(end 0.12065 -0.2794)
			(stroke
				(width 0.1)
				(type default)
			)
			(layer "F.Fab")
		)
		(fp_line
			(start -0.12065 -0.305054)
			(end -0.12065 -0.2794)
			(stroke
				(width 0.1)
				(type default)
			)
			(layer "F.Fab")
		)
		(fp_line
			(start -0.67945 0.3048)
			(end -0.67945 -0.305054)
			(stroke
				(width 0.1)
				(type default)
			)
			(layer "F.Fab")
		)
		(fp_line
			(start -0.67945 -0.305054)
			(end -0.12065 -0.305054)
			(stroke
				(width 0.1)
				(type default)
			)
			(layer "F.Fab")
		)
		(pad "1" smd circle
			(at -0.40005 0 180)
			(size 0 0)
			(layers "F.Cu" "F.Mask" "F.Paste")
			(net "P3V3_AUX")
		)
		(pad "2" smd circle
			(at 0.40005 0 180)
			(size 0 0)
			(layers "F.Cu" "F.Mask" "F.Paste")
			(net "SMB_FRU_3V3AUX_SCL")
		)
	)
	(footprint ""
		(layer "F.Cu")
		(at 54.811168 -160.047178)
		(property "Reference" "PC444_P1_1"
			(at 0 0 0)
			(layer "F.SilkS")
			(hide yes)
			(effects
				(font
					(size 1.27 1.27)
				)
			)
		)
		(property "Value" ""
			(at 0 0 0)
			(layer "F.Fab")
			(effects
				(font
					(size 1.27 1.27)
				)
			)
		)
		(duplicate_pad_numbers_are_jumpers no)
		(fp_line
			(start -0.7874 -0.4064)
			(end 0.7874 -0.4064)
			(stroke
				(width 0.1524)
				(type default)
			)
			(layer "F.SilkS")
		)
		(fp_line
			(start -0.7874 0.4064)
			(end -0.7874 -0.4064)
			(stroke
				(width 0.1524)
				(type default)
			)
			(layer "F.SilkS")
		)
		(fp_line
			(start 0.7874 -0.4064)
			(end 0.7874 0.4064)
			(stroke
				(width 0.1524)
				(type default)
			)
			(layer "F.SilkS")
		)
		(fp_line
			(start 0.7874 0.4064)
			(end -0.7874 0.4064)
			(stroke
				(width 0.1524)
				(type default)
			)
			(layer "F.SilkS")
		)
		(fp_line
			(start -0.67945 -0.305054)
			(end -0.12065 -0.305054)
			(stroke
				(width 0.1)
				(type default)
			)
			(layer "F.Fab")
		)
		(fp_line
			(start -0.67945 0.3048)
			(end -0.67945 -0.305054)
			(stroke
				(width 0.1)
				(type default)
			)
			(layer "F.Fab")
		)
		(fp_line
			(start -0.12065 -0.305054)
			(end -0.12065 -0.2794)
			(stroke
				(width 0.1)
				(type default)
			)
			(layer "F.Fab")
		)
		(fp_line
			(start -0.12065 -0.2794)
			(end 0.12065 -0.2794)
			(stroke
				(width 0.1)
				(type default)
			)
			(layer "F.Fab")
		)
		(fp_line
			(start -0.12065 0.2794)
			(end -0.12065 0.3048)
			(stroke
				(width 0.1)
				(type default)
			)
			(layer "F.Fab")
		)
		(fp_line
			(start -0.12065 0.3048)
			(end -0.67945 0.3048)
			(stroke
				(width 0.1)
				(type default)
			)
			(layer "F.Fab")
		)
		(fp_line
			(start 0.120396 0.2794)
			(end -0.12065 0.2794)
			(stroke
				(width 0.1)
				(type default)
			)
			(layer "F.Fab")
		)
		(fp_line
			(start 0.120396 0.3048)
			(end 0.120396 0.2794)
			(stroke
				(width 0.1)
				(type default)
			)
			(layer "F.Fab")
		)
		(fp_line
			(start 0.12065 -0.3048)
			(end 0.67945 -0.3048)
			(stroke
				(width 0.1)
				(type default)
			)
			(layer "F.Fab")
		)
		(fp_line
			(start 0.12065 -0.2794)
			(end 0.12065 -0.3048)
			(stroke
				(width 0.1)
				(type default)
			)
			(layer "F.Fab")
		)
		(fp_line
			(start 0.67945 -0.3048)
			(end 0.67945 0.3048)
			(stroke
				(width 0.1)
				(type default)
			)
			(layer "F.Fab")
		)
		(fp_line
			(start 0.67945 0.3048)
			(end 0.120396 0.3048)
			(stroke
				(width 0.1)
				(type default)
			)
			(layer "F.Fab")
		)
		(pad "1" smd circle
			(at -0.40005 0)
			(size 0 0)
			(layers "F.Cu" "F.Mask" "F.Paste")
			(net "SW_P12V_PVCCINFAON_CPU1_FLT")
		)
		(pad "2" smd circle
			(at 0.40005 0)
			(size 0 0)
			(layers "F.Cu" "F.Mask" "F.Paste")
			(net "GND")
		)
	)
	(footprint ""
		(layer "F.Cu")
		(at 280.20645 -394.17117)
		(property "Reference" "PR2538"
			(at 0 0 0)
			(layer "F.SilkS")
			(hide yes)
			(effects
				(font
					(size 1.27 1.27)
				)
			)
		)
		(property "Value" ""
			(at 0 0 0)
			(layer "F.Fab")
			(effects
				(font
					(size 1.27 1.27)
				)
			)
		)
		(duplicate_pad_numbers_are_jumpers no)
		(fp_line
			(start -0.7874 -0.4064)
			(end 0.7874 -0.4064)
			(stroke
				(width 0.1524)
				(type default)
			)
			(layer "F.SilkS")
		)
		(fp_line
			(start -0.7874 0.4064)
			(end -0.7874 -0.4064)
			(stroke
				(width 0.1524)
				(type default)
			)
			(layer "F.SilkS")
		)
		(fp_line
			(start 0.7874 -0.4064)
			(end 0.7874 0.4064)
			(stroke
				(width 0.1524)
				(type default)
			)
			(layer "F.SilkS")
		)
		(fp_line
			(start 0.7874 0.4064)
			(end -0.7874 0.4064)
			(stroke
				(width 0.1524)
				(type default)
			)
			(layer "F.SilkS")
		)
		(fp_line
			(start -0.67945 -0.305054)
			(end -0.12065 -0.305054)
			(stroke
				(width 0.1)
				(type default)
			)
			(layer "F.Fab")
		)
		(fp_line
			(start -0.67945 0.3048)
			(end -0.67945 -0.305054)
			(stroke
				(width 0.1)
				(type default)
			)
			(layer "F.Fab")
		)
		(fp_line
			(start -0.12065 -0.305054)
			(end -0.12065 -0.2794)
			(stroke
				(width 0.1)
				(type default)
			)
			(layer "F.Fab")
		)
		(fp_line
			(start -0.12065 -0.2794)
			(end 0.12065 -0.2794)
			(stroke
				(width 0.1)
				(type default)
			)
			(layer "F.Fab")
		)
		(fp_line
			(start -0.12065 0.2794)
			(end -0.12065 0.3048)
			(stroke
				(width 0.1)
				(type default)
			)
			(layer "F.Fab")
		)
		(fp_line
			(start -0.12065 0.3048)
			(end -0.67945 0.3048)
			(stroke
				(width 0.1)
				(type default)
			)
			(layer "F.Fab")
		)
		(fp_line
			(start 0.120396 0.2794)
			(end -0.12065 0.2794)
			(stroke
				(width 0.1)
				(type default)
			)
			(layer "F.Fab")
		)
		(fp_line
			(start 0.120396 0.3048)
			(end 0.120396 0.2794)
			(stroke
				(width 0.1)
				(type default)
			)
			(layer "F.Fab")
		)
		(fp_line
			(start 0.12065 -0.3048)
			(end 0.67945 -0.3048)
			(stroke
				(width 0.1)
				(type default)
			)
			(layer "F.Fab")
		)
		(fp_line
			(start 0.12065 -0.2794)
			(end 0.12065 -0.3048)
			(stroke
				(width 0.1)
				(type default)
			)
			(layer "F.Fab")
		)
		(fp_line
			(start 0.67945 -0.3048)
			(end 0.67945 0.3048)
			(stroke
				(width 0.1)
				(type default)
			)
			(layer "F.Fab")
		)
		(fp_line
			(start 0.67945 0.3048)
			(end 0.120396 0.3048)
			(stroke
				(width 0.1)
				(type default)
			)
			(layer "F.Fab")
		)
		(pad "1" smd circle
			(at -0.40005 0)
			(size 0 0)
			(layers "F.Cu" "F.Mask" "F.Paste")
			(net "MB0_CM_GATE_G0")
		)
		(pad "2" smd circle
			(at 0.40005 0)
			(size 0 0)
			(layers "F.Cu" "F.Mask" "F.Paste")
			(net "P12V_HSC_GATE1")
		)
	)
	(footprint ""
		(layer "F.Cu")
		(at 361.573826 -365.290354 90)
		(property "Reference" "PC1173"
			(at 0 0 90)
			(layer "F.SilkS")
			(hide yes)
			(effects
				(font
					(size 1.27 1.27)
				)
			)
		)
		(property "Value" ""
			(at 0 0 90)
			(layer "F.Fab")
			(effects
				(font
					(size 1.27 1.27)
				)
			)
		)
		(duplicate_pad_numbers_are_jumpers no)
		(fp_line
			(start 0.7874 -0.4064)
			(end 0.7874 0.4064)
			(stroke
				(width 0.1524)
				(type default)
			)
			(layer "F.SilkS")
		)
		(fp_line
			(start -0.7874 -0.4064)
			(end 0.7874 -0.4064)
			(stroke
				(width 0.1524)
				(type default)
			)
			(layer "F.SilkS")
		)
		(fp_line
			(start 0.7874 0.4064)
			(end -0.7874 0.4064)
			(stroke
				(width 0.1524)
				(type default)
			)
			(layer "F.SilkS")
		)
		(fp_line
			(start -0.7874 0.4064)
			(end -0.7874 -0.4064)
			(stroke
				(width 0.1524)
				(type default)
			)
			(layer "F.SilkS")
		)
		(fp_line
			(start -0.12065 -0.305054)
			(end -0.12065 -0.2794)
			(stroke
				(width 0.1)
				(type default)
			)
			(layer "F.Fab")
		)
		(fp_line
			(start -0.67945 -0.305054)
			(end -0.12065 -0.305054)
			(stroke
				(width 0.1)
				(type default)
			)
			(layer "F.Fab")
		)
		(fp_line
			(start 0.67945 -0.3048)
			(end 0.67945 0.3048)
			(stroke
				(width 0.1)
				(type default)
			)
			(layer "F.Fab")
		)
		(fp_line
			(start 0.12065 -0.3048)
			(end 0.67945 -0.3048)
			(stroke
				(width 0.1)
				(type default)
			)
			(layer "F.Fab")
		)
		(fp_line
			(start 0.12065 -0.2794)
			(end 0.12065 -0.3048)
			(stroke
				(width 0.1)
				(type default)
			)
			(layer "F.Fab")
		)
		(fp_line
			(start -0.12065 -0.2794)
			(end 0.12065 -0.2794)
			(stroke
				(width 0.1)
				(type default)
			)
			(layer "F.Fab")
		)
		(fp_line
			(start 0.120396 0.2794)
			(end -0.12065 0.2794)
			(stroke
				(width 0.1)
				(type default)
			)
			(layer "F.Fab")
		)
		(fp_line
			(start -0.12065 0.2794)
			(end -0.12065 0.3048)
			(stroke
				(width 0.1)
				(type default)
			)
			(layer "F.Fab")
		)
		(fp_line
			(start 0.67945 0.3048)
			(end 0.120396 0.3048)
			(stroke
				(width 0.1)
				(type default)
			)
			(layer "F.Fab")
		)
		(fp_line
			(start 0.120396 0.3048)
			(end 0.120396 0.2794)
			(stroke
				(width 0.1)
				(type default)
			)
			(layer "F.Fab")
		)
		(fp_line
			(start -0.12065 0.3048)
			(end -0.67945 0.3048)
			(stroke
				(width 0.1)
				(type default)
			)
			(layer "F.Fab")
		)
		(fp_line
			(start -0.67945 0.3048)
			(end -0.67945 -0.305054)
			(stroke
				(width 0.1)
				(type default)
			)
			(layer "F.Fab")
		)
		(pad "1" smd circle
			(at -0.40005 0 90)
			(size 0 0)
			(layers "F.Cu" "F.Mask" "F.Paste")
			(net "PVCCIN_CPU0_VREF")
		)
		(pad "2" smd circle
			(at 0.40005 0 90)
			(size 0 0)
			(layers "F.Cu" "F.Mask" "F.Paste")
			(net "GND")
		)
	)
)
